(kicad_pcb
	(version 20241229)
	(generator "pcbnew")
	(generator_version "9.0")
	(general
		(thickness 1.294)
		(legacy_teardrops no)
	)
	(paper "A3")
	(title_block
		(title "Kintex 410T devboard")
		(date "2024-04-03")
		(rev "1.1.2")
		(comment 9 "footprints 892-897 of 975")
	)
	(layers
		(0 "F.Cu" mixed)
		(4 "In1.Cu" power)
		(6 "In2.Cu" power)
		(8 "In3.Cu" mixed)
		(10 "In4.Cu" power)
		(12 "In5.Cu" mixed)
		(14 "In6.Cu" power)
		(16 "In7.Cu" mixed)
		(18 "In8.Cu" power)
		(2 "B.Cu" mixed)
		(9 "F.Adhes" user "F.Adhesive")
		(11 "B.Adhes" user "B.Adhesive")
		(13 "F.Paste" user)
		(15 "B.Paste" user)
		(5 "F.SilkS" user "F.Silkscreen")
		(7 "B.SilkS" user "B.Silkscreen")
		(1 "F.Mask" user)
		(3 "B.Mask" user)
		(17 "Dwgs.User" user "User.Drawings")
		(19 "Cmts.User" user "User.Comments")
		(21 "Eco1.User" user "User.Eco1")
		(23 "Eco2.User" user "User.Eco2")
		(25 "Edge.Cuts" user)
		(27 "Margin" user)
		(31 "F.CrtYd" user "F.Courtyard")
		(29 "B.CrtYd" user "B.Courtyard")
		(35 "F.Fab" user)
		(33 "B.Fab" user)
	)
	(footprint "antmicro-footprints:C_0201"
		(layer "B.Cu")
		(at 202.65 131.6 -90)
		(descr "Capacitor SMD 0201")
		(tags "capacitor SMD 0201")
		(property "Reference" "C135"
			(at -30.65 -27 90)
			(layer "B.SilkS")
			(effects
				(font
					(size 0.7 0.7)
					(thickness 0.15)
				)
				(justify left bottom mirror)
			)
		)
		(property "Value" "C_100n_0201"
			(at 0 -1.4 90)
			(layer "B.Fab")
			(effects
				(font
					(size 0.7 0.7)
					(thickness 0.15)
				)
				(justify left bottom mirror)
			)
		)
		(property "Description" "SMD Multilayer Ceramic Capacitor, 0.1 µF, 6.3 V, 0201 [0603 Metric], ± 10%, X6S, CC Series"
			(at 0 0 270)
			(layer "F.Fab")
			(hide yes)
			(effects
				(font
					(size 1.27 1.27)
					(thickness 0.15)
				)
			)
		)
		(property "Author" "Antmicro"
			(at 71.05 334.25 0)
			(layer "B.Fab")
			(hide yes)
			(effects
				(font
					(size 1 1)
					(thickness 0.15)
				)
				(justify mirror)
			)
		)
		(property "Dielectric" ""
			(at 71.05 334.25 0)
			(layer "B.Fab")
			(hide yes)
			(effects
				(font
					(size 1 1)
					(thickness 0.15)
				)
				(justify mirror)
			)
		)
		(property "License" "Apache-2.0"
			(at 71.05 334.25 0)
			(layer "B.Fab")
			(hide yes)
			(effects
				(font
					(size 1 1)
					(thickness 0.15)
				)
				(justify mirror)
			)
		)
		(property "MPN" "CC0201KRX6S5BB104"
			(at 71.05 334.25 0)
			(layer "B.Fab")
			(hide yes)
			(effects
				(font
					(size 1 1)
					(thickness 0.15)
				)
				(justify mirror)
			)
		)
		(property "Manufacturer" "YAGEO"
			(at 71.05 334.25 0)
			(layer "B.Fab")
			(hide yes)
			(effects
				(font
					(size 1 1)
					(thickness 0.15)
				)
				(justify mirror)
			)
		)
		(property "Val" "100n"
			(at 71.05 334.25 0)
			(layer "B.Fab")
			(hide yes)
			(effects
				(font
					(size 1 1)
					(thickness 0.15)
				)
				(justify mirror)
			)
		)
		(property "Voltage" ""
			(at 71.05 334.25 0)
			(layer "B.Fab")
			(hide yes)
			(effects
				(font
					(size 1 1)
					(thickness 0.15)
				)
				(justify mirror)
			)
		)
		(sheetname "FPGA supply")
		(sheetfile "fpga-supply.kicad_sch")
		(attr smd)
		(fp_rect
			(start -0.7 0.35)
			(end 0.7 -0.35)
			(stroke
				(width 0.05)
				(type default)
			)
			(fill no)
			(layer "B.CrtYd")
		)
		(fp_rect
			(start 0.3 -0.15)
			(end -0.301 0.149)
			(stroke
				(width 0.15)
				(type solid)
			)
			(fill no)
			(layer "B.Fab")
		)
		(pad "" smd roundrect
			(at -0.349 0.002 270)
			(size 0.318 0.36)
			(layers "B.Paste")
			(roundrect_rratio 0.25)
		)
		(pad "" smd roundrect
			(at 0.341 0.002 270)
			(size 0.318 0.36)
			(layers "B.Paste")
			(roundrect_rratio 0.25)
		)
		(pad "1" smd roundrect
			(at -0.321 0.002 270)
			(size 0.46 0.4)
			(layers "B.Cu" "B.Mask")
			(roundrect_rratio 0.25)
			(net 1 "GND")
			(pintype "passive")
		)
		(pad "2" smd roundrect
			(at 0.32 0.002 270)
			(size 0.46 0.4)
			(layers "B.Cu" "B.Mask")
			(roundrect_rratio 0.25)
			(net 650 "+1V0")
			(pintype "passive")
		)
	)
	(footprint "antmicro-footprints:R_0402_1005Metric"
		(layer "B.Cu")
		(at 203.101 74.233 -90)
		(descr "Resistor SMD 0402")
		(tags "resistor SMD 0402")
		(property "Reference" "R3"
			(at 0.742 -0.399 90)
			(layer "B.SilkS")
			(effects
				(font
					(size 0.7 0.7)
					(thickness 0.15)
				)
				(justify left bottom mirror)
			)
		)
		(property "Value" "R_10k_0402"
			(at 0 -1.4 90)
			(layer "B.Fab")
			(effects
				(font
					(size 0.7 0.7)
					(thickness 0.15)
				)
				(justify left bottom mirror)
			)
		)
		(property "Description" "SMD Chip Resistor, 10 kohm, ± 1%, 62.5 mW, 0402 [1005 Metric], Thick Film, General Purpose"
			(at 0 0 270)
			(layer "F.Fab")
			(hide yes)
			(effects
				(font
					(size 1.27 1.27)
					(thickness 0.15)
				)
			)
		)
		(property "Author" "Antmicro"
			(at 128.868 277.334 0)
			(layer "B.Fab")
			(hide yes)
			(effects
				(font
					(size 1 1)
					(thickness 0.15)
				)
				(justify mirror)
			)
		)
		(property "DNP" "DNP"
			(at 128.868 277.334 0)
			(layer "B.Fab")
			(hide yes)
			(effects
				(font
					(size 1 1)
					(thickness 0.15)
				)
				(justify mirror)
			)
		)
		(property "License" "Apache-2.0"
			(at 128.868 277.334 0)
			(layer "B.Fab")
			(hide yes)
			(effects
				(font
					(size 1 1)
					(thickness 0.15)
				)
				(justify mirror)
			)
		)
		(property "MPN" "CR0402-FX-1002GLF"
			(at 128.868 277.334 0)
			(layer "B.Fab")
			(hide yes)
			(effects
				(font
					(size 1 1)
					(thickness 0.15)
				)
				(justify mirror)
			)
		)
		(property "Manufacturer" "Bourns"
			(at 128.868 277.334 0)
			(layer "B.Fab")
			(hide yes)
			(effects
				(font
					(size 1 1)
					(thickness 0.15)
				)
				(justify mirror)
			)
		)
		(property "Tolerance" "1%"
			(at 128.868 277.334 0)
			(layer "B.Fab")
			(hide yes)
			(effects
				(font
					(size 1 1)
					(thickness 0.15)
				)
				(justify mirror)
			)
		)
		(property "Val" "10k"
			(at 128.868 277.334 0)
			(layer "B.Fab")
			(hide yes)
			(effects
				(font
					(size 1 1)
					(thickness 0.15)
				)
				(justify mirror)
			)
		)
		(property "dnp" ""
			(at 128.868 277.334 0)
			(layer "B.Fab")
			(hide yes)
			(effects
				(font
					(size 1 1)
					(thickness 0.15)
				)
				(justify mirror)
			)
		)
		(property "exclude_from_bom" ""
			(at 128.868 277.334 0)
			(layer "B.Fab")
			(hide yes)
			(effects
				(font
					(size 1 1)
					(thickness 0.15)
				)
				(justify mirror)
			)
		)
		(sheetname "FPGA Config")
		(sheetfile "fpga-config.kicad_sch")
		(attr smd exclude_from_bom)
		(fp_rect
			(start -0.925 0.47)
			(end 0.925 -0.47)
			(stroke
				(width 0.05)
				(type default)
			)
			(fill no)
			(layer "B.CrtYd")
		)
		(fp_rect
			(start -0.5 0.25)
			(end 0.5 -0.25)
			(stroke
				(width 0.15)
				(type solid)
			)
			(fill no)
			(layer "B.Fab")
		)
		(pad "1" smd roundrect
			(at -0.48 0 270)
			(size 0.59 0.64)
			(layers "B.Cu" "B.Mask" "B.Paste")
			(roundrect_rratio 0.25)
			(net 24 "+3V3")
			(pintype "passive")
		)
		(pad "2" smd roundrect
			(at 0.48 0 270)
			(size 0.59 0.64)
			(layers "B.Cu" "B.Mask" "B.Paste")
			(roundrect_rratio 0.25)
			(net 299 "/FPGA Config/MODE1")
			(pintype "passive")
		)
	)
	(footprint "antmicro-footprints:R_0402_1005Metric"
		(layer "B.Cu")
		(at 180.05 175.2625 -90)
		(descr "Resistor SMD 0402")
		(tags "resistor SMD 0402")
		(property "Reference" "R319"
			(at 0.7125 -0.375 90)
			(layer "B.SilkS")
			(effects
				(font
					(size 0.7 0.7)
					(thickness 0.15)
				)
				(justify left bottom mirror)
			)
		)
		(property "Value" "R_0R_0402"
			(at 0 -1.4 90)
			(layer "B.Fab")
			(effects
				(font
					(size 0.7 0.7)
					(thickness 0.15)
				)
				(justify left bottom mirror)
			)
		)
		(property "Description" "SMD Chip Resistor, Jumper, 0 ohm, 100 mW, 0402 [1005 Metric], Thick Film, General Purpose"
			(at 0 0 270)
			(layer "F.Fab")
			(hide yes)
			(effects
				(font
					(size 1.27 1.27)
					(thickness 0.15)
				)
			)
		)
		(property "Author" "Antmicro"
			(at 4.7875 355.3125 0)
			(layer "B.Fab")
			(hide yes)
			(effects
				(font
					(size 1 1)
					(thickness 0.15)
				)
				(justify mirror)
			)
		)
		(property "Current" "1A"
			(at 4.7875 355.3125 0)
			(layer "B.Fab")
			(hide yes)
			(effects
				(font
					(size 1 1)
					(thickness 0.15)
				)
				(justify mirror)
			)
		)
		(property "DNP" "DNP"
			(at 4.7875 355.3125 0)
			(layer "B.Fab")
			(hide yes)
			(effects
				(font
					(size 1 1)
					(thickness 0.15)
				)
				(justify mirror)
			)
		)
		(property "License" "Apache-2.0"
			(at 4.7875 355.3125 0)
			(layer "B.Fab")
			(hide yes)
			(effects
				(font
					(size 1 1)
					(thickness 0.15)
				)
				(justify mirror)
			)
		)
		(property "MPN" "ERJ2GE0R00X"
			(at 4.7875 355.3125 0)
			(layer "B.Fab")
			(hide yes)
			(effects
				(font
					(size 1 1)
					(thickness 0.15)
				)
				(justify mirror)
			)
		)
		(property "Manufacturer" "Panasonic"
			(at 4.7875 355.3125 0)
			(layer "B.Fab")
			(hide yes)
			(effects
				(font
					(size 1 1)
					(thickness 0.15)
				)
				(justify mirror)
			)
		)
		(property "Tolerance" ""
			(at 4.7875 355.3125 0)
			(layer "B.Fab")
			(hide yes)
			(effects
				(font
					(size 1 1)
					(thickness 0.15)
				)
				(justify mirror)
			)
		)
		(property "Val" "0R"
			(at 4.7875 355.3125 0)
			(layer "B.Fab")
			(hide yes)
			(effects
				(font
					(size 1 1)
					(thickness 0.15)
				)
				(justify mirror)
			)
		)
		(property "dnp" ""
			(at 4.7875 355.3125 0)
			(layer "B.Fab")
			(hide yes)
			(effects
				(font
					(size 1 1)
					(thickness 0.15)
				)
				(justify mirror)
			)
		)
		(property "exclude_from_bom" ""
			(at 4.7875 355.3125 0)
			(layer "B.Fab")
			(hide yes)
			(effects
				(font
					(size 1 1)
					(thickness 0.15)
				)
				(justify mirror)
			)
		)
		(sheetname "DC-DC Converters")
		(sheetfile "dc-dc.kicad_sch")
		(attr smd exclude_from_bom)
		(fp_rect
			(start -0.925 0.47)
			(end 0.925 -0.47)
			(stroke
				(width 0.05)
				(type default)
			)
			(fill no)
			(layer "B.CrtYd")
		)
		(fp_rect
			(start -0.5 0.25)
			(end 0.5 -0.25)
			(stroke
				(width 0.15)
				(type solid)
			)
			(fill no)
			(layer "B.Fab")
		)
		(pad "1" smd roundrect
			(at -0.48 0 270)
			(size 0.59 0.64)
			(layers "B.Cu" "B.Mask" "B.Paste")
			(roundrect_rratio 0.25)
			(net 964 "/DC-DC Converters/FB7")
			(pintype "passive")
		)
		(pad "2" smd roundrect
			(at 0.48 0 270)
			(size 0.59 0.64)
			(layers "B.Cu" "B.Mask" "B.Paste")
			(roundrect_rratio 0.25)
			(net 1214 "/DC-DC Converters/SENSE_5V_P")
			(pintype "passive")
		)
	)
	(footprint "antmicro-footprints:R_0402_1005Metric"
		(layer "B.Cu")
		(at 193.1 79.8 90)
		(descr "Resistor SMD 0402")
		(tags "resistor SMD 0402")
		(property "Reference" "R147"
			(at -0.725 0.4 270)
			(layer "B.SilkS")
			(effects
				(font
					(size 0.7 0.7)
					(thickness 0.15)
				)
				(justify left bottom mirror)
			)
		)
		(property "Value" "R_100R_0402"
			(at 0 -1.4 270)
			(layer "B.Fab")
			(effects
				(font
					(size 0.7 0.7)
					(thickness 0.15)
				)
				(justify left bottom mirror)
			)
		)
		(property "Description" "SMD Chip Resistor, 100 ohm, ± 1%, 62.5 mW, 0402 [1005 Metric], Thick Film, General Purpose"
			(at 0 0 90)
			(layer "F.Fab")
			(hide yes)
			(effects
				(font
					(size 1.27 1.27)
					(thickness 0.15)
				)
			)
		)
		(property "Author" "Antmicro"
			(at 272.9 -113.3 0)
			(layer "B.Fab")
			(hide yes)
			(effects
				(font
					(size 1 1)
					(thickness 0.15)
				)
				(justify mirror)
			)
		)
		(property "License" "Apache-2.0"
			(at 272.9 -113.3 0)
			(layer "B.Fab")
			(hide yes)
			(effects
				(font
					(size 1 1)
					(thickness 0.15)
				)
				(justify mirror)
			)
		)
		(property "MPN" "CR0402-FX-1000GLF"
			(at 272.9 -113.3 0)
			(layer "B.Fab")
			(hide yes)
			(effects
				(font
					(size 1 1)
					(thickness 0.15)
				)
				(justify mirror)
			)
		)
		(property "Manufacturer" "Bourns"
			(at 272.9 -113.3 0)
			(layer "B.Fab")
			(hide yes)
			(effects
				(font
					(size 1 1)
					(thickness 0.15)
				)
				(justify mirror)
			)
		)
		(property "Tolerance" "1%"
			(at 272.9 -113.3 0)
			(layer "B.Fab")
			(hide yes)
			(effects
				(font
					(size 1 1)
					(thickness 0.15)
				)
				(justify mirror)
			)
		)
		(property "Val" "100R"
			(at 272.9 -113.3 0)
			(layer "B.Fab")
			(hide yes)
			(effects
				(font
					(size 1 1)
					(thickness 0.15)
				)
				(justify mirror)
			)
		)
		(sheetname "User GPIO + LED + button + DIP switch")
		(sheetfile "user-gpio.kicad_sch")
		(attr smd)
		(fp_rect
			(start -0.925 0.47)
			(end 0.925 -0.47)
			(stroke
				(width 0.05)
				(type default)
			)
			(fill no)
			(layer "B.CrtYd")
		)
		(fp_rect
			(start -0.5 0.25)
			(end 0.5 -0.25)
			(stroke
				(width 0.15)
				(type solid)
			)
			(fill no)
			(layer "B.Fab")
		)
		(pad "1" smd roundrect
			(at -0.48 0 90)
			(size 0.59 0.64)
			(layers "B.Cu" "B.Mask" "B.Paste")
			(roundrect_rratio 0.25)
			(net 493 "/FPGA Bank 12 & 13/CW_HEADER.IO4")
			(pintype "passive")
		)
		(pad "2" smd roundrect
			(at 0.48 0 90)
			(size 0.59 0.64)
			(layers "B.Cu" "B.Mask" "B.Paste")
			(roundrect_rratio 0.25)
			(net 1145 "/User GPIO + LED + button + DIP switch/CW_20PIN_IO4")
			(pintype "passive")
		)
	)
	(footprint "antmicro-footprints:C_0201"
		(layer "B.Cu")
		(at 189.8 123.5 180)
		(descr "Capacitor SMD 0201")
		(tags "capacitor SMD 0201")
		(property "Reference" "C152"
			(at 0.525 -0.35 0)
			(layer "B.SilkS")
			(effects
				(font
					(size 0.7 0.7)
					(thickness 0.15)
				)
				(justify left bottom mirror)
			)
		)
		(property "Value" "C_100n_0201"
			(at 0 -1.4 0)
			(layer "B.Fab")
			(effects
				(font
					(size 0.7 0.7)
					(thickness 0.15)
				)
				(justify left bottom mirror)
			)
		)
		(property "Description" "SMD Multilayer Ceramic Capacitor, 0.1 µF, 6.3 V, 0201 [0603 Metric], ± 10%, X6S, CC Series"
			(at 0 0 180)
			(layer "F.Fab")
			(hide yes)
			(effects
				(font
					(size 1.27 1.27)
					(thickness 0.15)
				)
			)
		)
		(property "Author" "Antmicro"
			(at 379.6 247 0)
			(layer "B.Fab")
			(hide yes)
			(effects
				(font
					(size 1 1)
					(thickness 0.15)
				)
				(justify mirror)
			)
		)
		(property "Dielectric" ""
			(at 379.6 247 0)
			(layer "B.Fab")
			(hide yes)
			(effects
				(font
					(size 1 1)
					(thickness 0.15)
				)
				(justify mirror)
			)
		)
		(property "License" "Apache-2.0"
			(at 379.6 247 0)
			(layer "B.Fab")
			(hide yes)
			(effects
				(font
					(size 1 1)
					(thickness 0.15)
				)
				(justify mirror)
			)
		)
		(property "MPN" "CC0201KRX6S5BB104"
			(at 379.6 247 0)
			(layer "B.Fab")
			(hide yes)
			(effects
				(font
					(size 1 1)
					(thickness 0.15)
				)
				(justify mirror)
			)
		)
		(property "Manufacturer" "YAGEO"
			(at 379.6 247 0)
			(layer "B.Fab")
			(hide yes)
			(effects
				(font
					(size 1 1)
					(thickness 0.15)
				)
				(justify mirror)
			)
		)
		(property "Val" "100n"
			(at 379.6 247 0)
			(layer "B.Fab")
			(hide yes)
			(effects
				(font
					(size 1 1)
					(thickness 0.15)
				)
				(justify mirror)
			)
		)
		(property "Voltage" ""
			(at 379.6 247 0)
			(layer "B.Fab")
			(hide yes)
			(effects
				(font
					(size 1 1)
					(thickness 0.15)
				)
				(justify mirror)
			)
		)
		(sheetname "FPGA supply")
		(sheetfile "fpga-supply.kicad_sch")
		(attr smd)
		(fp_rect
			(start -0.7 0.35)
			(end 0.7 -0.35)
			(stroke
				(width 0.05)
				(type default)
			)
			(fill no)
			(layer "B.CrtYd")
		)
		(fp_rect
			(start 0.3 -0.15)
			(end -0.301 0.149)
			(stroke
				(width 0.15)
				(type solid)
			)
			(fill no)
			(layer "B.Fab")
		)
		(pad "" smd roundrect
			(at -0.349 0.002 180)
			(size 0.318 0.36)
			(layers "B.Paste")
			(roundrect_rratio 0.25)
		)
		(pad "" smd roundrect
			(at 0.341 0.002 180)
			(size 0.318 0.36)
			(layers "B.Paste")
			(roundrect_rratio 0.25)
		)
		(pad "1" smd roundrect
			(at -0.321 0.002 180)
			(size 0.46 0.4)
			(layers "B.Cu" "B.Mask")
			(roundrect_rratio 0.25)
			(net 1 "GND")
			(pintype "passive")
		)
		(pad "2" smd roundrect
			(at 0.32 0.002 180)
			(size 0.46 0.4)
			(layers "B.Cu" "B.Mask")
			(roundrect_rratio 0.25)
			(net 8 "+1V2_MGTAVTT")
			(pintype "passive")
		)
	)
	(footprint "antmicro-footprints:R_0402_1005Metric"
		(layer "B.Cu")
		(at 221.715 149.216)
		(descr "Resistor SMD 0402")
		(tags "resistor SMD 0402")
		(property "Reference" "R228"
			(at 0.96 2.334 180)
			(layer "B.SilkS")
			(effects
				(font
					(size 0.7 0.7)
					(thickness 0.15)
				)
				(justify left bottom mirror)
			)
		)
		(property "Value" "R_2k2_0402"
			(at 0 -1.4 180)
			(layer "B.Fab")
			(effects
				(font
					(size 0.7 0.7)
					(thickness 0.15)
				)
				(justify left bottom mirror)
			)
		)
		(property "Description" "SMD Chip Resistor, 2.2 kohm, ± 1%, 62.5 mW, 0402 [1005 Metric], Thick Film, General Purpose"
			(at 0 0 0)
			(layer "F.Fab")
			(hide yes)
			(effects
				(font
					(size 1.27 1.27)
					(thickness 0.15)
				)
			)
		)
		(property "Author" "Antmicro"
			(at 0 0 0)
			(layer "B.Fab")
			(hide yes)
			(effects
				(font
					(size 1 1)
					(thickness 0.15)
				)
				(justify mirror)
			)
		)
		(property "DNP" "DNP"
			(at 0 0 0)
			(layer "B.Fab")
			(hide yes)
			(effects
				(font
					(size 1 1)
					(thickness 0.15)
				)
				(justify mirror)
			)
		)
		(property "License" "Apache-2.0"
			(at 0 0 0)
			(layer "B.Fab")
			(hide yes)
			(effects
				(font
					(size 1 1)
					(thickness 0.15)
				)
				(justify mirror)
			)
		)
		(property "MPN" "CR0402-FX-2201GLF"
			(at 0 0 0)
			(layer "B.Fab")
			(hide yes)
			(effects
				(font
					(size 1 1)
					(thickness 0.15)
				)
				(justify mirror)
			)
		)
		(property "Manufacturer" "Bourns"
			(at 0 0 0)
			(layer "B.Fab")
			(hide yes)
			(effects
				(font
					(size 1 1)
					(thickness 0.15)
				)
				(justify mirror)
			)
		)
		(property "Tolerance" "1%"
			(at 0 0 0)
			(layer "B.Fab")
			(hide yes)
			(effects
				(font
					(size 1 1)
					(thickness 0.15)
				)
				(justify mirror)
			)
		)
		(property "Val" "2k2"
			(at 0 0 0)
			(layer "B.Fab")
			(hide yes)
			(effects
				(font
					(size 1 1)
					(thickness 0.15)
				)
				(justify mirror)
			)
		)
		(property "dnp" ""
			(at 0 0 0)
			(layer "B.Fab")
			(hide yes)
			(effects
				(font
					(size 1 1)
					(thickness 0.15)
				)
				(justify mirror)
			)
		)
		(property "exclude_from_bom" ""
			(at 0 0 0)
			(layer "B.Fab")
			(hide yes)
			(effects
				(font
					(size 1 1)
					(thickness 0.15)
				)
				(justify mirror)
			)
		)
		(sheetname "HDMI + Ethernet")
		(sheetfile "hdmi-ethernet.kicad_sch")
		(attr smd exclude_from_bom)
		(fp_rect
			(start -0.925 0.47)
			(end 0.925 -0.47)
			(stroke
				(width 0.05)
				(type default)
			)
			(fill no)
			(layer "B.CrtYd")
		)
		(fp_rect
			(start -0.5 0.25)
			(end 0.5 -0.25)
			(stroke
				(width 0.15)
				(type solid)
			)
			(fill no)
			(layer "B.Fab")
		)
		(pad "1" smd roundrect
			(at -0.48 0)
			(size 0.59 0.64)
			(layers "B.Cu" "B.Mask" "B.Paste")
			(roundrect_rratio 0.25)
			(net 947 "/HDMI + Ethernet/ETH_PHY_RXER")
			(pintype "passive")
		)
		(pad "2" smd roundrect
			(at 0.48 0)
			(size 0.59 0.64)
			(layers "B.Cu" "B.Mask" "B.Paste")
			(roundrect_rratio 0.25)
			(net 1 "GND")
			(pintype "passive")
		)
	)
)
